("..\\packaged\\pstdmlmodels.dat" 
 (PackagedDevice 
  ("DEFAULT_RESISTOR_1000.000000OHM_2_1" 
   (ESpice ".subckt DEFAULT_RESISTOR_1000.000000OHM_2_1 1 2
R1 1 2 1000
.ends DEFAULT_RESISTOR_1000.000000OHM_2_1
" ) 
   (PinConnections 
    (1 2 ) 
    (2 1 ) ) ) 
  (DEFAULT_CAPACITOR_100000pF_1_2 
   (ESpice ".subckt DEFAULT_CAPACITOR_100000pF_1_2 2 1
C1 2 1 1e-007
.ends DEFAULT_CAPACITOR_100000pF_1_2
" ) 
   (PinConnections 
    (2 1 ) 
    (1 2 ) ) ) 
  (DEFAULT_RESISTOR_33OHM_2_1 
   (ESpice ".subckt DEFAULT_RESISTOR_33OHM_2_1 1 2
R1 1 2 33
.ends DEFAULT_RESISTOR_33OHM_2_1
" ) 
   (PinConnections 
    (1 2 ) 
    (2 1 ) ) ) ) 
 (LibraryVersion 136.2 ) ) 